# BASEBOARD_FAB2 (Tioga Pass) — schematic netlist excerpt (pin names and nets, part order shuffled) for the footprints in the layout excerpt that follows; sources: Cadence DE-HDL packaged netlist, KiCad conversion of Wiwynn_Tioga_Pass_MB.brd

R8R1  RES  49.9 1% CHIP  pkg 0402  page 56 : A = PD_CPU1_RSVD_TEST_1 ; B = GND
U1R1  TTL1G07_A  74LVC1G07 IC  pkg SOP  page 170 : A = FM_FAST_PROCHOT_THROTTLE_DLY_BU ; Y = FM_THROTTLE_R1_N
C6L8  CAPP  220UF 4V 20% POSCAP  pkg 7343  page 234 : A = PVPP_KLM ; B = GND

(kicad_pcb
	(version 20260206)
	(generator "pcbnew")
	(generator_version "10.0")
	(general
		(thickness 1.6)
		(legacy_teardrops no)
	)
	(paper "A4")
	(title_block
		(title "Wiwynn_Tioga_Pass_MB.brd")
		(comment 1 "Tioga Pass / footprints 2747-2749 of 4770")
	)
	(layers
		(0 "F.Cu" signal "TOP")
		(4 "In1.Cu" signal "L2GND")
		(6 "In2.Cu" signal "L3")
		(8 "In3.Cu" signal "L4GND")
		(10 "In4.Cu" signal "L5")
		(12 "In5.Cu" signal "L6GND")
		(14 "In6.Cu" signal "L7VCC")
		(16 "In7.Cu" signal "L8VCC")
		(18 "In8.Cu" signal "L9GND")
		(20 "In9.Cu" signal "L10")
		(22 "In10.Cu" signal "L11GND")
		(24 "In11.Cu" signal "L12")
		(26 "In12.Cu" signal "L13GND")
		(2 "B.Cu" signal "BOTTOM")
		(9 "F.Adhes" user "F.Adhesive")
		(11 "B.Adhes" user "B.Adhesive")
		(13 "F.Paste" user "Package Geometry/Pastemask Top")
		(15 "B.Paste" user "Package Geometry/Pastemask Bottom")
		(5 "F.SilkS" user "Ref Des/Silkscreen Top")
		(7 "B.SilkS" user "Ref Des/Silkscreen Bottom")
		(1 "F.Mask" user "Board Geometry/Soldermask Top")
		(3 "B.Mask" user "Board Geometry/Soldermask Bottom")
		(17 "Dwgs.User" user "User.Drawings")
		(19 "Cmts.User" user "User.Comments")
		(21 "Eco1.User" user "User.Eco1")
		(23 "Eco2.User" user "User.Eco2")
		(25 "Edge.Cuts" user "Board Geometry/Outline")
		(27 "Margin" user)
		(31 "F.CrtYd" user "Package Geometry/Place Bound Top")
		(29 "B.CrtYd" user "Package Geometry/Place Bound Bottom")
		(35 "F.Fab" user "Ref Des/Assembly Top")
		(33 "B.Fab" user "Ref Des/Assembly Bottom")
	)
	(footprint ""
		(layer "B.Cu")
		(at 169.6466 -142.8242 90)
		(property "Reference" "C6L8"
			(at -3.15087 3.4544 0)
			(unlocked yes)
			(layer "B.SilkS")
			(effects
				(font
					(size 0.7874 0.5842)
					(thickness 0.1524)
				)
				(justify left mirror)
			)
		)
		(property "Value" ""
			(at 0 0 90)
			(layer "B.Fab")
			(effects
				(font
					(size 1.27 1.27)
				)
				(justify mirror)
			)
		)
		(duplicate_pad_numbers_are_jumpers no)
		(fp_line
			(start 2.032 -1.524)
			(end 2.032 1.524)
			(stroke
				(width 0.1524)
				(type default)
			)
			(layer "B.SilkS")
		)
		(fp_line
			(start 1.7272 -1.524)
			(end 2.032 -1.524)
			(stroke
				(width 0.1524)
				(type default)
			)
			(layer "B.SilkS")
		)
		(fp_line
			(start -1.7272 -1.524)
			(end -2.032 -1.524)
			(stroke
				(width 0.1524)
				(type default)
			)
			(layer "B.SilkS")
		)
		(fp_line
			(start -2.032 -1.524)
			(end -2.032 1.524)
			(stroke
				(width 0.1524)
				(type default)
			)
			(layer "B.SilkS")
		)
		(fp_line
			(start 2.2987 -0.2413)
			(end 2.2987 7.3533)
			(stroke
				(width 0.1524)
				(type default)
			)
			(layer "B.SilkS")
		)
		(fp_line
			(start 2.032 -0.2413)
			(end 2.2987 -0.2413)
			(stroke
				(width 0.1524)
				(type default)
			)
			(layer "B.SilkS")
		)
		(fp_line
			(start -2.2987 -0.2413)
			(end -2.032 -0.2413)
			(stroke
				(width 0.1524)
				(type default)
			)
			(layer "B.SilkS")
		)
		(fp_line
			(start 2.032 1.524)
			(end 1.7272 1.524)
			(stroke
				(width 0.1524)
				(type default)
			)
			(layer "B.SilkS")
		)
		(fp_line
			(start -2.032 1.524)
			(end -1.7272 1.524)
			(stroke
				(width 0.1524)
				(type default)
			)
			(layer "B.SilkS")
		)
		(fp_line
			(start 2.2987 7.3533)
			(end 1.7272 7.3533)
			(stroke
				(width 0.1524)
				(type default)
			)
			(layer "B.SilkS")
		)
		(fp_line
			(start -1.7272 7.3533)
			(end -2.2987 7.3533)
			(stroke
				(width 0.1524)
				(type default)
			)
			(layer "B.SilkS")
		)
		(fp_line
			(start -2.2987 7.3533)
			(end -2.2987 -0.2413)
			(stroke
				(width 0.1524)
				(type default)
			)
			(layer "B.SilkS")
		)
		(fp_poly
			(pts
				(xy 2.2987 -0.2413) (xy -2.2987 -0.2413) (xy -2.2987 7.3533) (xy 2.2987 7.3533)
			)
			(stroke
				(width 0)
				(type default)
			)
			(fill no)
			(layer "B.CrtYd")
		)
		(fp_line
			(start 2.2987 -0.2413)
			(end -2.2987 -0.2413)
			(stroke
				(width 0.1)
				(type default)
			)
			(layer "B.Fab")
		)
		(fp_line
			(start -2.2987 -0.2413)
			(end -2.2987 7.3533)
			(stroke
				(width 0.1)
				(type default)
			)
			(layer "B.Fab")
		)
		(fp_line
			(start 2.2987 7.3533)
			(end 2.2987 -0.2413)
			(stroke
				(width 0.1)
				(type default)
			)
			(layer "B.Fab")
		)
		(fp_line
			(start -2.2987 7.3533)
			(end 2.2987 7.3533)
			(stroke
				(width 0.1)
				(type default)
			)
			(layer "B.Fab")
		)
		(pad "1" smd rect
			(at 0 0 270)
			(size 2.54 3.048)
			(layers "B.Cu" "B.Mask" "B.Paste")
			(net "PVPP_KLM")
		)
		(pad "2" smd rect
			(at 0 7.112 270)
			(size 2.54 3.048)
			(layers "B.Cu" "B.Mask" "B.Paste")
			(net "GND")
		)
	)
	(footprint ""
		(layer "B.Cu")
		(at 420.503604 -75.048872 180)
		(property "Reference" "U1R1"
			(at -1.24333 2.032 270)
			(unlocked yes)
			(layer "B.SilkS")
			(effects
				(font
					(size 0.7874 0.5842)
					(thickness 0.1524)
				)
				(justify left mirror)
			)
		)
		(property "Value" ""
			(at 0 0 0)
			(layer "B.Fab")
			(effects
				(font
					(size 1.27 1.27)
				)
				(justify mirror)
			)
		)
		(duplicate_pad_numbers_are_jumpers no)
		(fp_circle
			(center 0.351536 -0.648462)
			(end 0.224536 -0.648462)
			(stroke
				(width 0.254)
				(type default)
			)
			(fill no)
			(layer "B.SilkS")
		)
		(fp_poly
			(pts
				(xy -0.21463 -0.450088) (xy -1.56337 -0.450088) (xy -1.56337 1.75006) (xy -0.21463 1.75006)
			)
			(stroke
				(width 0)
				(type default)
			)
			(fill no)
			(layer "B.CrtYd")
		)
		(fp_line
			(start -0.21463 1.75006)
			(end -0.21463 -0.450088)
			(stroke
				(width 0.1)
				(type default)
			)
			(layer "B.Fab")
		)
		(fp_line
			(start -0.21463 -0.450088)
			(end -1.56337 -0.450088)
			(stroke
				(width 0.1)
				(type default)
			)
			(layer "B.Fab")
		)
		(fp_line
			(start -1.56337 1.75006)
			(end -0.21463 1.75006)
			(stroke
				(width 0.1)
				(type default)
			)
			(layer "B.Fab")
		)
		(fp_line
			(start -1.56337 -0.450088)
			(end -1.56337 1.75006)
			(stroke
				(width 0.1)
				(type default)
			)
			(layer "B.Fab")
		)
		(fp_circle
			(center 0.4699 -0.8382)
			(end 0.3429 -0.8382)
			(stroke
				(width 0.254)
				(type default)
			)
			(fill no)
			(layer "B.Fab")
		)
		(pad "1" smd rect
			(at 0 0)
			(size 1.016 0.381)
			(layers "B.Cu" "B.Mask" "B.Paste")
			(net "Net_6472")
		)
		(pad "2" smd rect
			(at 0 0.649986)
			(size 1.016 0.381)
			(layers "B.Cu" "B.Mask" "B.Paste")
			(net "FM_FAST_PROCHOT_THROTTLE_DLY_BU")
		)
		(pad "3" smd rect
			(at 0 1.299972)
			(size 1.016 0.381)
			(layers "B.Cu" "B.Mask" "B.Paste")
			(net "GND")
		)
		(pad "4" smd rect
			(at -1.778 1.299972)
			(size 1.016 0.381)
			(layers "B.Cu" "B.Mask" "B.Paste")
			(net "FM_THROTTLE_R1_N")
		)
		(pad "5" smd rect
			(at -1.778 0)
			(size 1.016 0.381)
			(layers "B.Cu" "B.Mask" "B.Paste")
			(net "P3V3_STBY")
		)
	)
	(footprint ""
		(layer "B.Cu")
		(at 80.391 -64.262 -90)
		(property "Reference" "R8R1"
			(at 0 0 90)
			(layer "B.SilkS")
			(hide yes)
			(effects
				(font
					(size 1.27 1.27)
				)
				(justify mirror)
			)
		)
		(property "Value" ""
			(at 0 0 90)
			(layer "B.Fab")
			(effects
				(font
					(size 1.27 1.27)
				)
				(justify mirror)
			)
		)
		(duplicate_pad_numbers_are_jumpers no)
		(fp_poly
			(pts
				(xy 0.2794 -0.1016) (xy -0.2794 -0.1016) (xy -0.2794 0.9906) (xy 0.2794 0.9906)
			)
			(stroke
				(width 0)
				(type default)
			)
			(fill no)
			(layer "B.CrtYd")
		)
		(fp_line
			(start -0.2794 0.9906)
			(end -0.2794 -0.1016)
			(stroke
				(width 0.1)
				(type default)
			)
			(layer "B.Fab")
		)
		(fp_line
			(start 0.2794 0.9906)
			(end -0.2794 0.9906)
			(stroke
				(width 0.1)
				(type default)
			)
			(layer "B.Fab")
		)
		(fp_line
			(start -0.2794 -0.1016)
			(end 0.2794 -0.1016)
			(stroke
				(width 0.1)
				(type default)
			)
			(layer "B.Fab")
		)
		(fp_line
			(start 0.2794 -0.1016)
			(end 0.2794 0.9906)
			(stroke
				(width 0.1)
				(type default)
			)
			(layer "B.Fab")
		)
		(pad "1" smd rect
			(at 0 0 90)
			(size 0.508 0.508)
			(layers "B.Cu" "B.Mask" "B.Paste")
			(net "PD_CPU1_RSVD_TEST_1")
		)
		(pad "2" smd rect
			(at 0 0.889 90)
			(size 0.508 0.508)
			(layers "B.Cu" "B.Mask" "B.Paste")
			(net "GND")
		)
		(zone
			(layer "B.Cu")
			(hatch none 0.5)
			(connect_pads
				(clearance 0)
			)
			(min_thickness 0.25)
			(keepout
				(tracks not_allowed)
				(vias allowed)
				(pads allowed)
				(copperpour not_allowed)
				(footprints allowed)
			)
			(placement
				(enabled no)
				(sheetname "")
			)
			(fill
				(thermal_gap 0.5)
				(thermal_bridge_width 0.5)
				(island_removal_mode 0)
			)
			(polygon
				(pts
					(xy 79.756 -64.008) (xy 79.756 -64.516) (xy 80.137 -64.516) (xy 80.137 -64.008)
				)
			)
		)
		(zone
			(layer "B.Cu")
			(hatch none 0.5)
			(connect_pads
				(clearance 0)
			)
			(min_thickness 0.25)
			(keepout
				(tracks allowed)
				(vias not_allowed)
				(pads allowed)
				(copperpour not_allowed)
				(footprints allowed)
			)
			(placement
				(enabled no)
				(sheetname "")
			)
			(fill
				(thermal_gap 0.5)
				(thermal_bridge_width 0.5)
				(island_removal_mode 0)
			)
			(polygon
				(pts
					(xy 80.137 -64.008) (xy 80.137 -64.516) (xy 79.756 -64.516) (xy 79.756 -64.008)
				)
			)
		)
	)
)
